# T6G (Grand Teton) — schematic netlist excerpt (pin names and nets, part order shuffled) for the footprints in the layout excerpt that follows; sources: Cadence DE-HDL packaged netlist, KiCad conversion of 04192023_DAF0TMB3IC0_F0TG_MB_C_brd_V02_OCP.brd

H6002  HOLE  EMPTY  pkg TH  page 230 : \1\ = GND
PR8002  Q_RES  2.2 1% CHIP  pkg 0402LF  page 226 : A = SW_PVDD18_S5_P1_BST ; B = SW_PVDD18_S5_P1_BST_R

(kicad_pcb
	(version 20260206)
	(generator "pcbnew")
	(generator_version "10.0")
	(general
		(thickness 1.6)
		(legacy_teardrops no)
	)
	(paper "A4")
	(title_block
		(title "04192023_DAF0TMB3IC0_F0TG_MB_C_brd_V02_OCP.brd")
		(comment 1 "Grand Teton / footprints 3098-3099 of 8354")
	)
	(layers
		(0 "F.Cu" signal "TOP")
		(4 "In1.Cu" signal "GND")
		(6 "In2.Cu" signal "IN1")
		(8 "In3.Cu" signal "GND1")
		(10 "In4.Cu" signal "IN2")
		(12 "In5.Cu" signal "GND2")
		(14 "In6.Cu" signal "IN3")
		(16 "In7.Cu" signal "GND3")
		(18 "In8.Cu" signal "VCC")
		(20 "In9.Cu" signal "VCC1")
		(22 "In10.Cu" signal "GND4")
		(24 "In11.Cu" signal "IN4")
		(26 "In12.Cu" signal "GND5")
		(28 "In13.Cu" signal "IN5")
		(30 "In14.Cu" signal "GND6")
		(32 "In15.Cu" signal "IN6")
		(34 "In16.Cu" signal "GND7")
		(2 "B.Cu" signal "BOTTOM")
		(9 "F.Adhes" user "F.Adhesive")
		(11 "B.Adhes" user "B.Adhesive")
		(13 "F.Paste" user "Package Geometry/Pastemask Top")
		(15 "B.Paste" user "Package Geometry/Pastemask Bottom")
		(5 "F.SilkS" user "Ref Des/Silkscreen Top")
		(7 "B.SilkS" user "Ref Des/Silkscreen Bottom")
		(1 "F.Mask" user "Board Geometry/Soldermask Top")
		(3 "B.Mask" user "Board Geometry/Soldermask Bottom")
		(17 "Dwgs.User" user "User.Drawings")
		(19 "Cmts.User" user "User.Comments")
		(21 "Eco1.User" user "User.Eco1")
		(23 "Eco2.User" user "User.Eco2")
		(25 "Edge.Cuts" user "Board Geometry/Outline")
		(27 "Margin" user)
		(31 "F.CrtYd" user "Package Geometry/Place Bound Top")
		(29 "B.CrtYd" user "Package Geometry/Place Bound Bottom")
		(35 "F.Fab" user "Ref Des/Assembly Top")
		(33 "B.Fab" user "Ref Des/Assembly Bottom")
	)
	(footprint ""
		(layer "F.Cu")
		(at 67.021964 -149.721316 -90)
		(property "Reference" "PR8002"
			(at 0 0 270)
			(layer "F.SilkS")
			(hide yes)
			(effects
				(font
					(size 1.27 1.27)
				)
			)
		)
		(property "Value" ""
			(at 0 0 270)
			(layer "F.Fab")
			(effects
				(font
					(size 1.27 1.27)
				)
			)
		)
		(duplicate_pad_numbers_are_jumpers no)
		(fp_line
			(start -0.7874 0.4064)
			(end -0.7874 -0.4064)
			(stroke
				(width 0.1524)
				(type default)
			)
			(layer "F.SilkS")
		)
		(fp_line
			(start 0.7874 0.4064)
			(end -0.7874 0.4064)
			(stroke
				(width 0.1524)
				(type default)
			)
			(layer "F.SilkS")
		)
		(fp_line
			(start -0.7874 -0.4064)
			(end 0.7874 -0.4064)
			(stroke
				(width 0.1524)
				(type default)
			)
			(layer "F.SilkS")
		)
		(fp_line
			(start 0.7874 -0.4064)
			(end 0.7874 0.4064)
			(stroke
				(width 0.1524)
				(type default)
			)
			(layer "F.SilkS")
		)
		(fp_line
			(start -0.67945 0.3048)
			(end -0.67945 -0.305054)
			(stroke
				(width 0.1)
				(type default)
			)
			(layer "F.Fab")
		)
		(fp_line
			(start -0.12065 0.3048)
			(end -0.67945 0.3048)
			(stroke
				(width 0.1)
				(type default)
			)
			(layer "F.Fab")
		)
		(fp_line
			(start 0.120396 0.3048)
			(end 0.120396 0.2794)
			(stroke
				(width 0.1)
				(type default)
			)
			(layer "F.Fab")
		)
		(fp_line
			(start 0.67945 0.3048)
			(end 0.120396 0.3048)
			(stroke
				(width 0.1)
				(type default)
			)
			(layer "F.Fab")
		)
		(fp_line
			(start -0.12065 0.2794)
			(end -0.12065 0.3048)
			(stroke
				(width 0.1)
				(type default)
			)
			(layer "F.Fab")
		)
		(fp_line
			(start 0.120396 0.2794)
			(end -0.12065 0.2794)
			(stroke
				(width 0.1)
				(type default)
			)
			(layer "F.Fab")
		)
		(fp_line
			(start -0.12065 -0.2794)
			(end 0.12065 -0.2794)
			(stroke
				(width 0.1)
				(type default)
			)
			(layer "F.Fab")
		)
		(fp_line
			(start 0.12065 -0.2794)
			(end 0.12065 -0.3048)
			(stroke
				(width 0.1)
				(type default)
			)
			(layer "F.Fab")
		)
		(fp_line
			(start 0.12065 -0.3048)
			(end 0.67945 -0.3048)
			(stroke
				(width 0.1)
				(type default)
			)
			(layer "F.Fab")
		)
		(fp_line
			(start 0.67945 -0.3048)
			(end 0.67945 0.3048)
			(stroke
				(width 0.1)
				(type default)
			)
			(layer "F.Fab")
		)
		(fp_line
			(start -0.67945 -0.305054)
			(end -0.12065 -0.305054)
			(stroke
				(width 0.1)
				(type default)
			)
			(layer "F.Fab")
		)
		(fp_line
			(start -0.12065 -0.305054)
			(end -0.12065 -0.2794)
			(stroke
				(width 0.1)
				(type default)
			)
			(layer "F.Fab")
		)
		(pad "1" smd circle
			(at -0.40005 0 270)
			(size 0 0)
			(layers "F.Cu" "F.Mask" "F.Paste")
			(net "SW_PVDD18_S5_P1_BST")
		)
		(pad "2" smd circle
			(at 0.40005 0 270)
			(size 0 0)
			(layers "F.Cu" "F.Mask" "F.Paste")
			(net "SW_PVDD18_S5_P1_BST_R")
		)
	)
	(footprint ""
		(layer "F.Cu")
		(at 225.429826 -388.160514 -90)
		(property "Reference" "H6002"
			(at 0.127 -6.738112 90)
			(unlocked yes)
			(layer "F.SilkS")
			(effects
				(font
					(size 0.7874 0.5842)
					(thickness 0.1524)
				)
				(justify left)
			)
		)
		(property "Value" ""
			(at 0 0 270)
			(layer "F.Fab")
			(effects
				(font
					(size 1.27 1.27)
				)
			)
		)
		(duplicate_pad_numbers_are_jumpers no)
		(pad "1" thru_hole circle
			(at 0 0 270)
			(size 8.001 8.001)
			(drill 4.2164)
			(layers "*.Cu" "*.Mask")
			(remove_unused_layers no)
			(net "GND")
			(clearance -1.6383)
		)
	)
)
